# T6G (Grand Teton) — schematic netlist excerpt (pin names and nets, part order shuffled) for the footprints in the layout excerpt that follows; sources: Cadence DE-HDL packaged netlist, KiCad conversion of 04192023_DAF0TMB3IC0_F0TG_MB_C_brd_V02_OCP.brd

PC1848  Q_CAP  1UF 25V 10% X6S  pkg C0402  page 189 : A = P5V_AUX_VCC ; B = GND
R18  Q_RES  10K 1% CHIP  pkg 0402LF  page 83 : A = RST_CPU1_PERST0_N ; B = GND

(kicad_pcb
	(version 20260206)
	(generator "pcbnew")
	(generator_version "10.0")
	(general
		(thickness 1.6)
		(legacy_teardrops no)
	)
	(paper "A4")
	(title_block
		(title "04192023_DAF0TMB3IC0_F0TG_MB_C_brd_V02_OCP.brd")
		(comment 1 "Grand Teton / footprints 3480-3481 of 8354")
	)
	(layers
		(0 "F.Cu" signal "TOP")
		(4 "In1.Cu" signal "GND")
		(6 "In2.Cu" signal "IN1")
		(8 "In3.Cu" signal "GND1")
		(10 "In4.Cu" signal "IN2")
		(12 "In5.Cu" signal "GND2")
		(14 "In6.Cu" signal "IN3")
		(16 "In7.Cu" signal "GND3")
		(18 "In8.Cu" signal "VCC")
		(20 "In9.Cu" signal "VCC1")
		(22 "In10.Cu" signal "GND4")
		(24 "In11.Cu" signal "IN4")
		(26 "In12.Cu" signal "GND5")
		(28 "In13.Cu" signal "IN5")
		(30 "In14.Cu" signal "GND6")
		(32 "In15.Cu" signal "IN6")
		(34 "In16.Cu" signal "GND7")
		(2 "B.Cu" signal "BOTTOM")
		(9 "F.Adhes" user "F.Adhesive")
		(11 "B.Adhes" user "B.Adhesive")
		(13 "F.Paste" user "Package Geometry/Pastemask Top")
		(15 "B.Paste" user "Package Geometry/Pastemask Bottom")
		(5 "F.SilkS" user "Ref Des/Silkscreen Top")
		(7 "B.SilkS" user "Ref Des/Silkscreen Bottom")
		(1 "F.Mask" user "Board Geometry/Soldermask Top")
		(3 "B.Mask" user "Board Geometry/Soldermask Bottom")
		(17 "Dwgs.User" user "User.Drawings")
		(19 "Cmts.User" user "User.Comments")
		(21 "Eco1.User" user "User.Eco1")
		(23 "Eco2.User" user "User.Eco2")
		(25 "Edge.Cuts" user "Board Geometry/Outline")
		(27 "Margin" user)
		(31 "F.CrtYd" user "Package Geometry/Place Bound Top")
		(29 "B.CrtYd" user "Package Geometry/Place Bound Bottom")
		(35 "F.Fab" user "Ref Des/Assembly Top")
		(33 "B.Fab" user "Ref Des/Assembly Bottom")
	)
	(footprint ""
		(layer "F.Cu")
		(at 177.927 -137.632948 90)
		(property "Reference" "R18"
			(at 0 0 90)
			(layer "F.SilkS")
			(hide yes)
			(effects
				(font
					(size 1.27 1.27)
				)
			)
		)
		(property "Value" ""
			(at 0 0 90)
			(layer "F.Fab")
			(effects
				(font
					(size 1.27 1.27)
				)
			)
		)
		(duplicate_pad_numbers_are_jumpers no)
		(fp_line
			(start 0.7874 -0.4064)
			(end 0.7874 0.4064)
			(stroke
				(width 0.1524)
				(type default)
			)
			(layer "F.SilkS")
		)
		(fp_line
			(start -0.7874 -0.4064)
			(end 0.7874 -0.4064)
			(stroke
				(width 0.1524)
				(type default)
			)
			(layer "F.SilkS")
		)
		(fp_line
			(start 0.7874 0.4064)
			(end -0.7874 0.4064)
			(stroke
				(width 0.1524)
				(type default)
			)
			(layer "F.SilkS")
		)
		(fp_line
			(start -0.7874 0.4064)
			(end -0.7874 -0.4064)
			(stroke
				(width 0.1524)
				(type default)
			)
			(layer "F.SilkS")
		)
		(fp_line
			(start -0.12065 -0.305054)
			(end -0.12065 -0.2794)
			(stroke
				(width 0.1)
				(type default)
			)
			(layer "F.Fab")
		)
		(fp_line
			(start -0.67945 -0.305054)
			(end -0.12065 -0.305054)
			(stroke
				(width 0.1)
				(type default)
			)
			(layer "F.Fab")
		)
		(fp_line
			(start 0.67945 -0.3048)
			(end 0.67945 0.3048)
			(stroke
				(width 0.1)
				(type default)
			)
			(layer "F.Fab")
		)
		(fp_line
			(start 0.12065 -0.3048)
			(end 0.67945 -0.3048)
			(stroke
				(width 0.1)
				(type default)
			)
			(layer "F.Fab")
		)
		(fp_line
			(start 0.12065 -0.2794)
			(end 0.12065 -0.3048)
			(stroke
				(width 0.1)
				(type default)
			)
			(layer "F.Fab")
		)
		(fp_line
			(start -0.12065 -0.2794)
			(end 0.12065 -0.2794)
			(stroke
				(width 0.1)
				(type default)
			)
			(layer "F.Fab")
		)
		(fp_line
			(start 0.120396 0.2794)
			(end -0.12065 0.2794)
			(stroke
				(width 0.1)
				(type default)
			)
			(layer "F.Fab")
		)
		(fp_line
			(start -0.12065 0.2794)
			(end -0.12065 0.3048)
			(stroke
				(width 0.1)
				(type default)
			)
			(layer "F.Fab")
		)
		(fp_line
			(start 0.67945 0.3048)
			(end 0.120396 0.3048)
			(stroke
				(width 0.1)
				(type default)
			)
			(layer "F.Fab")
		)
		(fp_line
			(start 0.120396 0.3048)
			(end 0.120396 0.2794)
			(stroke
				(width 0.1)
				(type default)
			)
			(layer "F.Fab")
		)
		(fp_line
			(start -0.12065 0.3048)
			(end -0.67945 0.3048)
			(stroke
				(width 0.1)
				(type default)
			)
			(layer "F.Fab")
		)
		(fp_line
			(start -0.67945 0.3048)
			(end -0.67945 -0.305054)
			(stroke
				(width 0.1)
				(type default)
			)
			(layer "F.Fab")
		)
		(pad "1" smd circle
			(at -0.40005 0 90)
			(size 0 0)
			(layers "F.Cu" "F.Mask" "F.Paste")
			(net "RST_CPU1_PERST0_N")
		)
		(pad "2" smd circle
			(at 0.40005 0 90)
			(size 0 0)
			(layers "F.Cu" "F.Mask" "F.Paste")
			(net "GND")
		)
	)
	(footprint ""
		(layer "F.Cu")
		(at 416.136836 -142.185898 -90)
		(property "Reference" "PC1848"
			(at 0 0 270)
			(layer "F.SilkS")
			(hide yes)
			(effects
				(font
					(size 1.27 1.27)
				)
			)
		)
		(property "Value" ""
			(at 0 0 270)
			(layer "F.Fab")
			(effects
				(font
					(size 1.27 1.27)
				)
			)
		)
		(duplicate_pad_numbers_are_jumpers no)
		(fp_line
			(start -0.7874 0.4064)
			(end -0.7874 -0.4064)
			(stroke
				(width 0.1524)
				(type default)
			)
			(layer "F.SilkS")
		)
		(fp_line
			(start 0.7874 0.4064)
			(end -0.7874 0.4064)
			(stroke
				(width 0.1524)
				(type default)
			)
			(layer "F.SilkS")
		)
		(fp_line
			(start -0.7874 -0.4064)
			(end 0.7874 -0.4064)
			(stroke
				(width 0.1524)
				(type default)
			)
			(layer "F.SilkS")
		)
		(fp_line
			(start 0.7874 -0.4064)
			(end 0.7874 0.4064)
			(stroke
				(width 0.1524)
				(type default)
			)
			(layer "F.SilkS")
		)
		(fp_line
			(start -0.67945 0.3048)
			(end -0.67945 -0.305054)
			(stroke
				(width 0.1)
				(type default)
			)
			(layer "F.Fab")
		)
		(fp_line
			(start -0.12065 0.3048)
			(end -0.67945 0.3048)
			(stroke
				(width 0.1)
				(type default)
			)
			(layer "F.Fab")
		)
		(fp_line
			(start 0.120396 0.3048)
			(end 0.120396 0.2794)
			(stroke
				(width 0.1)
				(type default)
			)
			(layer "F.Fab")
		)
		(fp_line
			(start 0.67945 0.3048)
			(end 0.120396 0.3048)
			(stroke
				(width 0.1)
				(type default)
			)
			(layer "F.Fab")
		)
		(fp_line
			(start -0.12065 0.2794)
			(end -0.12065 0.3048)
			(stroke
				(width 0.1)
				(type default)
			)
			(layer "F.Fab")
		)
		(fp_line
			(start 0.120396 0.2794)
			(end -0.12065 0.2794)
			(stroke
				(width 0.1)
				(type default)
			)
			(layer "F.Fab")
		)
		(fp_line
			(start -0.12065 -0.2794)
			(end 0.12065 -0.2794)
			(stroke
				(width 0.1)
				(type default)
			)
			(layer "F.Fab")
		)
		(fp_line
			(start 0.12065 -0.2794)
			(end 0.12065 -0.3048)
			(stroke
				(width 0.1)
				(type default)
			)
			(layer "F.Fab")
		)
		(fp_line
			(start 0.12065 -0.3048)
			(end 0.67945 -0.3048)
			(stroke
				(width 0.1)
				(type default)
			)
			(layer "F.Fab")
		)
		(fp_line
			(start 0.67945 -0.3048)
			(end 0.67945 0.3048)
			(stroke
				(width 0.1)
				(type default)
			)
			(layer "F.Fab")
		)
		(fp_line
			(start -0.67945 -0.305054)
			(end -0.12065 -0.305054)
			(stroke
				(width 0.1)
				(type default)
			)
			(layer "F.Fab")
		)
		(fp_line
			(start -0.12065 -0.305054)
			(end -0.12065 -0.2794)
			(stroke
				(width 0.1)
				(type default)
			)
			(layer "F.Fab")
		)
		(pad "1" smd circle
			(at -0.40005 0 270)
			(size 0 0)
			(layers "F.Cu" "F.Mask" "F.Paste")
			(net "P5V_AUX_VCC")
		)
		(pad "2" smd circle
			(at 0.40005 0 270)
			(size 0 0)
			(layers "F.Cu" "F.Mask" "F.Paste")
			(net "GND")
		)
	)
)
